(kicad_pcb
	(version 20260206)
	(generator "pcbnew")
	(generator_version "10.0")
	(general
		(thickness 1.6)
		(legacy_teardrops no)
	)
	(paper "A4")
	(title_block
		(title "04192023_DAF0TMB3IC0_F0TG_MB_C_brd_V02_OCP.brd")
		(comment 1 "Grand Teton / footprints 4782-4788 of 8354")
	)
	(layers
		(0 "F.Cu" signal "TOP")
		(4 "In1.Cu" signal "GND")
		(6 "In2.Cu" signal "IN1")
		(8 "In3.Cu" signal "GND1")
		(10 "In4.Cu" signal "IN2")
		(12 "In5.Cu" signal "GND2")
		(14 "In6.Cu" signal "IN3")
		(16 "In7.Cu" signal "GND3")
		(18 "In8.Cu" signal "VCC")
		(20 "In9.Cu" signal "VCC1")
		(22 "In10.Cu" signal "GND4")
		(24 "In11.Cu" signal "IN4")
		(26 "In12.Cu" signal "GND5")
		(28 "In13.Cu" signal "IN5")
		(30 "In14.Cu" signal "GND6")
		(32 "In15.Cu" signal "IN6")
		(34 "In16.Cu" signal "GND7")
		(2 "B.Cu" signal "BOTTOM")
		(9 "F.Adhes" user "F.Adhesive")
		(11 "B.Adhes" user "B.Adhesive")
		(13 "F.Paste" user "Package Geometry/Pastemask Top")
		(15 "B.Paste" user "Package Geometry/Pastemask Bottom")
		(5 "F.SilkS" user "Ref Des/Silkscreen Top")
		(7 "B.SilkS" user "Ref Des/Silkscreen Bottom")
		(1 "F.Mask" user "Board Geometry/Soldermask Top")
		(3 "B.Mask" user "Board Geometry/Soldermask Bottom")
		(17 "Dwgs.User" user "User.Drawings")
		(19 "Cmts.User" user "User.Comments")
		(21 "Eco1.User" user "User.Eco1")
		(23 "Eco2.User" user "User.Eco2")
		(25 "Edge.Cuts" user "Board Geometry/Outline")
		(27 "Margin" user)
		(31 "F.CrtYd" user "Package Geometry/Place Bound Top")
		(29 "B.CrtYd" user "Package Geometry/Place Bound Bottom")
		(35 "F.Fab" user "Ref Des/Assembly Top")
		(33 "B.Fab" user "Ref Des/Assembly Bottom")
	)
	(footprint ""
		(layer "F.Cu")
		(at 89.131902 -373.03583 -90)
		(property "Reference" "C725"
			(at 0 0 270)
			(layer "F.SilkS")
			(hide yes)
			(effects
				(font
					(size 1.27 1.27)
				)
			)
		)
		(property "Value" ""
			(at 0 0 270)
			(layer "F.Fab")
			(effects
				(font
					(size 1.27 1.27)
				)
			)
		)
		(duplicate_pad_numbers_are_jumpers no)
		(fp_line
			(start -0.299974 0.150114)
			(end -0.299974 -0.150114)
			(stroke
				(width 0.1)
				(type default)
			)
			(layer "F.Fab")
		)
		(fp_line
			(start 0.299974 0.150114)
			(end -0.299974 0.150114)
			(stroke
				(width 0.1)
				(type default)
			)
			(layer "F.Fab")
		)
		(fp_line
			(start -0.299974 -0.150114)
			(end 0.299974 -0.150114)
			(stroke
				(width 0.1)
				(type default)
			)
			(layer "F.Fab")
		)
		(fp_line
			(start 0.299974 -0.150114)
			(end 0.299974 0.150114)
			(stroke
				(width 0.1)
				(type default)
			)
			(layer "F.Fab")
		)
		(pad "1" smd rect
			(at -0.2667 0 270)
			(size 0.3048 0.381)
			(layers "F.Cu" "F.Mask" "F.Paste")
			(net "P5E_CPU1_P1_TX_C_DP<8>")
		)
		(pad "2" smd rect
			(at 0.2667 0 270)
			(size 0.3048 0.381)
			(layers "F.Cu" "F.Mask" "F.Paste")
			(net "P5E_CPU1_P1_TX_DP<8>")
		)
	)
	(footprint ""
		(layer "F.Cu")
		(at 184.079642 -413.64408 -90)
		(property "Reference" "R2848"
			(at 0 0 270)
			(layer "F.SilkS")
			(hide yes)
			(effects
				(font
					(size 1.27 1.27)
				)
			)
		)
		(property "Value" ""
			(at 0 0 270)
			(layer "F.Fab")
			(effects
				(font
					(size 1.27 1.27)
				)
			)
		)
		(duplicate_pad_numbers_are_jumpers no)
		(fp_line
			(start -0.7874 0.4064)
			(end -0.7874 -0.4064)
			(stroke
				(width 0.1524)
				(type default)
			)
			(layer "F.SilkS")
		)
		(fp_line
			(start 0.7874 0.4064)
			(end -0.7874 0.4064)
			(stroke
				(width 0.1524)
				(type default)
			)
			(layer "F.SilkS")
		)
		(fp_line
			(start -0.7874 -0.4064)
			(end 0.7874 -0.4064)
			(stroke
				(width 0.1524)
				(type default)
			)
			(layer "F.SilkS")
		)
		(fp_line
			(start 0.7874 -0.4064)
			(end 0.7874 0.4064)
			(stroke
				(width 0.1524)
				(type default)
			)
			(layer "F.SilkS")
		)
		(fp_line
			(start -0.67945 0.3048)
			(end -0.67945 -0.305054)
			(stroke
				(width 0.1)
				(type default)
			)
			(layer "F.Fab")
		)
		(fp_line
			(start -0.12065 0.3048)
			(end -0.67945 0.3048)
			(stroke
				(width 0.1)
				(type default)
			)
			(layer "F.Fab")
		)
		(fp_line
			(start 0.120396 0.3048)
			(end 0.120396 0.2794)
			(stroke
				(width 0.1)
				(type default)
			)
			(layer "F.Fab")
		)
		(fp_line
			(start 0.67945 0.3048)
			(end 0.120396 0.3048)
			(stroke
				(width 0.1)
				(type default)
			)
			(layer "F.Fab")
		)
		(fp_line
			(start -0.12065 0.2794)
			(end -0.12065 0.3048)
			(stroke
				(width 0.1)
				(type default)
			)
			(layer "F.Fab")
		)
		(fp_line
			(start 0.120396 0.2794)
			(end -0.12065 0.2794)
			(stroke
				(width 0.1)
				(type default)
			)
			(layer "F.Fab")
		)
		(fp_line
			(start -0.12065 -0.2794)
			(end 0.12065 -0.2794)
			(stroke
				(width 0.1)
				(type default)
			)
			(layer "F.Fab")
		)
		(fp_line
			(start 0.12065 -0.2794)
			(end 0.12065 -0.3048)
			(stroke
				(width 0.1)
				(type default)
			)
			(layer "F.Fab")
		)
		(fp_line
			(start 0.12065 -0.3048)
			(end 0.67945 -0.3048)
			(stroke
				(width 0.1)
				(type default)
			)
			(layer "F.Fab")
		)
		(fp_line
			(start 0.67945 -0.3048)
			(end 0.67945 0.3048)
			(stroke
				(width 0.1)
				(type default)
			)
			(layer "F.Fab")
		)
		(fp_line
			(start -0.67945 -0.305054)
			(end -0.12065 -0.305054)
			(stroke
				(width 0.1)
				(type default)
			)
			(layer "F.Fab")
		)
		(fp_line
			(start -0.12065 -0.305054)
			(end -0.12065 -0.2794)
			(stroke
				(width 0.1)
				(type default)
			)
			(layer "F.Fab")
		)
		(pad "1" smd circle
			(at -0.40005 0 270)
			(size 0 0)
			(layers "F.Cu" "F.Mask" "F.Paste")
			(net "RST_SWB_BIC_N")
		)
		(pad "2" smd circle
			(at 0.40005 0 270)
			(size 0 0)
			(layers "F.Cu" "F.Mask" "F.Paste")
			(net "RST_SWB_BIC_R_N")
		)
	)
	(footprint ""
		(layer "F.Cu")
		(at 443.717172 -32.173418 90)
		(property "Reference" "PC2153"
			(at 0 0 90)
			(layer "F.SilkS")
			(hide yes)
			(effects
				(font
					(size 1.27 1.27)
				)
			)
		)
		(property "Value" ""
			(at 0 0 90)
			(layer "F.Fab")
			(effects
				(font
					(size 1.27 1.27)
				)
			)
		)
		(duplicate_pad_numbers_are_jumpers no)
		(fp_line
			(start 0.7874 -0.4064)
			(end 0.7874 0.4064)
			(stroke
				(width 0.1524)
				(type default)
			)
			(layer "F.SilkS")
		)
		(fp_line
			(start -0.7874 -0.4064)
			(end 0.7874 -0.4064)
			(stroke
				(width 0.1524)
				(type default)
			)
			(layer "F.SilkS")
		)
		(fp_line
			(start 0.7874 0.4064)
			(end -0.7874 0.4064)
			(stroke
				(width 0.1524)
				(type default)
			)
			(layer "F.SilkS")
		)
		(fp_line
			(start -0.7874 0.4064)
			(end -0.7874 -0.4064)
			(stroke
				(width 0.1524)
				(type default)
			)
			(layer "F.SilkS")
		)
		(fp_line
			(start -0.12065 -0.305054)
			(end -0.12065 -0.2794)
			(stroke
				(width 0.1)
				(type default)
			)
			(layer "F.Fab")
		)
		(fp_line
			(start -0.67945 -0.305054)
			(end -0.12065 -0.305054)
			(stroke
				(width 0.1)
				(type default)
			)
			(layer "F.Fab")
		)
		(fp_line
			(start 0.67945 -0.3048)
			(end 0.67945 0.3048)
			(stroke
				(width 0.1)
				(type default)
			)
			(layer "F.Fab")
		)
		(fp_line
			(start 0.12065 -0.3048)
			(end 0.67945 -0.3048)
			(stroke
				(width 0.1)
				(type default)
			)
			(layer "F.Fab")
		)
		(fp_line
			(start 0.12065 -0.2794)
			(end 0.12065 -0.3048)
			(stroke
				(width 0.1)
				(type default)
			)
			(layer "F.Fab")
		)
		(fp_line
			(start -0.12065 -0.2794)
			(end 0.12065 -0.2794)
			(stroke
				(width 0.1)
				(type default)
			)
			(layer "F.Fab")
		)
		(fp_line
			(start 0.120396 0.2794)
			(end -0.12065 0.2794)
			(stroke
				(width 0.1)
				(type default)
			)
			(layer "F.Fab")
		)
		(fp_line
			(start -0.12065 0.2794)
			(end -0.12065 0.3048)
			(stroke
				(width 0.1)
				(type default)
			)
			(layer "F.Fab")
		)
		(fp_line
			(start 0.67945 0.3048)
			(end 0.120396 0.3048)
			(stroke
				(width 0.1)
				(type default)
			)
			(layer "F.Fab")
		)
		(fp_line
			(start 0.120396 0.3048)
			(end 0.120396 0.2794)
			(stroke
				(width 0.1)
				(type default)
			)
			(layer "F.Fab")
		)
		(fp_line
			(start -0.12065 0.3048)
			(end -0.67945 0.3048)
			(stroke
				(width 0.1)
				(type default)
			)
			(layer "F.Fab")
		)
		(fp_line
			(start -0.67945 0.3048)
			(end -0.67945 -0.305054)
			(stroke
				(width 0.1)
				(type default)
			)
			(layer "F.Fab")
		)
		(pad "1" smd circle
			(at -0.40005 0 90)
			(size 0 0)
			(layers "F.Cu" "F.Mask" "F.Paste")
			(net "P12V_OCP_TIMER_1")
		)
		(pad "2" smd circle
			(at 0.40005 0 90)
			(size 0 0)
			(layers "F.Cu" "F.Mask" "F.Paste")
			(net "GND")
		)
	)
	(footprint ""
		(layer "F.Cu")
		(at 165.14064 -78.000606 180)
		(property "Reference" "R1009"
			(at 0 0 180)
			(layer "F.SilkS")
			(hide yes)
			(effects
				(font
					(size 1.27 1.27)
				)
			)
		)
		(property "Value" ""
			(at 0 0 180)
			(layer "F.Fab")
			(effects
				(font
					(size 1.27 1.27)
				)
			)
		)
		(duplicate_pad_numbers_are_jumpers no)
		(fp_line
			(start 0.7874 0.4064)
			(end -0.7874 0.4064)
			(stroke
				(width 0.1524)
				(type default)
			)
			(layer "F.SilkS")
		)
		(fp_line
			(start 0.7874 -0.4064)
			(end 0.7874 0.4064)
			(stroke
				(width 0.1524)
				(type default)
			)
			(layer "F.SilkS")
		)
		(fp_line
			(start -0.7874 0.4064)
			(end -0.7874 -0.4064)
			(stroke
				(width 0.1524)
				(type default)
			)
			(layer "F.SilkS")
		)
		(fp_line
			(start -0.7874 -0.4064)
			(end 0.7874 -0.4064)
			(stroke
				(width 0.1524)
				(type default)
			)
			(layer "F.SilkS")
		)
		(fp_line
			(start 0.67945 0.3048)
			(end 0.120396 0.3048)
			(stroke
				(width 0.1)
				(type default)
			)
			(layer "F.Fab")
		)
		(fp_line
			(start 0.67945 -0.3048)
			(end 0.67945 0.3048)
			(stroke
				(width 0.1)
				(type default)
			)
			(layer "F.Fab")
		)
		(fp_line
			(start 0.12065 -0.2794)
			(end 0.12065 -0.3048)
			(stroke
				(width 0.1)
				(type default)
			)
			(layer "F.Fab")
		)
		(fp_line
			(start 0.12065 -0.3048)
			(end 0.67945 -0.3048)
			(stroke
				(width 0.1)
				(type default)
			)
			(layer "F.Fab")
		)
		(fp_line
			(start 0.120396 0.3048)
			(end 0.120396 0.2794)
			(stroke
				(width 0.1)
				(type default)
			)
			(layer "F.Fab")
		)
		(fp_line
			(start 0.120396 0.2794)
			(end -0.12065 0.2794)
			(stroke
				(width 0.1)
				(type default)
			)
			(layer "F.Fab")
		)
		(fp_line
			(start -0.12065 0.3048)
			(end -0.67945 0.3048)
			(stroke
				(width 0.1)
				(type default)
			)
			(layer "F.Fab")
		)
		(fp_line
			(start -0.12065 0.2794)
			(end -0.12065 0.3048)
			(stroke
				(width 0.1)
				(type default)
			)
			(layer "F.Fab")
		)
		(fp_line
			(start -0.12065 -0.2794)
			(end 0.12065 -0.2794)
			(stroke
				(width 0.1)
				(type default)
			)
			(layer "F.Fab")
		)
		(fp_line
			(start -0.12065 -0.305054)
			(end -0.12065 -0.2794)
			(stroke
				(width 0.1)
				(type default)
			)
			(layer "F.Fab")
		)
		(fp_line
			(start -0.67945 0.3048)
			(end -0.67945 -0.305054)
			(stroke
				(width 0.1)
				(type default)
			)
			(layer "F.Fab")
		)
		(fp_line
			(start -0.67945 -0.305054)
			(end -0.12065 -0.305054)
			(stroke
				(width 0.1)
				(type default)
			)
			(layer "F.Fab")
		)
		(pad "1" smd circle
			(at -0.40005 0 180)
			(size 0 0)
			(layers "F.Cu" "F.Mask" "F.Paste")
			(net "P3V3_AUX")
		)
		(pad "2" smd circle
			(at 0.40005 0 180)
			(size 0 0)
			(layers "F.Cu" "F.Mask" "F.Paste")
			(net "IRQ_LVC3_WAKE")
		)
	)
	(footprint ""
		(layer "F.Cu")
		(at 303.653952 -22.7457 90)
		(property "Reference" "R1779"
			(at 0 0 90)
			(layer "F.SilkS")
			(hide yes)
			(effects
				(font
					(size 1.27 1.27)
				)
			)
		)
		(property "Value" ""
			(at 0 0 90)
			(layer "F.Fab")
			(effects
				(font
					(size 1.27 1.27)
				)
			)
		)
		(duplicate_pad_numbers_are_jumpers no)
		(fp_line
			(start 0.7874 -0.4064)
			(end 0.7874 0.4064)
			(stroke
				(width 0.1524)
				(type default)
			)
			(layer "F.SilkS")
		)
		(fp_line
			(start -0.7874 -0.4064)
			(end 0.7874 -0.4064)
			(stroke
				(width 0.1524)
				(type default)
			)
			(layer "F.SilkS")
		)
		(fp_line
			(start 0.7874 0.4064)
			(end -0.7874 0.4064)
			(stroke
				(width 0.1524)
				(type default)
			)
			(layer "F.SilkS")
		)
		(fp_line
			(start -0.7874 0.4064)
			(end -0.7874 -0.4064)
			(stroke
				(width 0.1524)
				(type default)
			)
			(layer "F.SilkS")
		)
		(fp_line
			(start -0.12065 -0.305054)
			(end -0.12065 -0.2794)
			(stroke
				(width 0.1)
				(type default)
			)
			(layer "F.Fab")
		)
		(fp_line
			(start -0.67945 -0.305054)
			(end -0.12065 -0.305054)
			(stroke
				(width 0.1)
				(type default)
			)
			(layer "F.Fab")
		)
		(fp_line
			(start 0.67945 -0.3048)
			(end 0.67945 0.3048)
			(stroke
				(width 0.1)
				(type default)
			)
			(layer "F.Fab")
		)
		(fp_line
			(start 0.12065 -0.3048)
			(end 0.67945 -0.3048)
			(stroke
				(width 0.1)
				(type default)
			)
			(layer "F.Fab")
		)
		(fp_line
			(start 0.12065 -0.2794)
			(end 0.12065 -0.3048)
			(stroke
				(width 0.1)
				(type default)
			)
			(layer "F.Fab")
		)
		(fp_line
			(start -0.12065 -0.2794)
			(end 0.12065 -0.2794)
			(stroke
				(width 0.1)
				(type default)
			)
			(layer "F.Fab")
		)
		(fp_line
			(start 0.120396 0.2794)
			(end -0.12065 0.2794)
			(stroke
				(width 0.1)
				(type default)
			)
			(layer "F.Fab")
		)
		(fp_line
			(start -0.12065 0.2794)
			(end -0.12065 0.3048)
			(stroke
				(width 0.1)
				(type default)
			)
			(layer "F.Fab")
		)
		(fp_line
			(start 0.67945 0.3048)
			(end 0.120396 0.3048)
			(stroke
				(width 0.1)
				(type default)
			)
			(layer "F.Fab")
		)
		(fp_line
			(start 0.120396 0.3048)
			(end 0.120396 0.2794)
			(stroke
				(width 0.1)
				(type default)
			)
			(layer "F.Fab")
		)
		(fp_line
			(start -0.12065 0.3048)
			(end -0.67945 0.3048)
			(stroke
				(width 0.1)
				(type default)
			)
			(layer "F.Fab")
		)
		(fp_line
			(start -0.67945 0.3048)
			(end -0.67945 -0.305054)
			(stroke
				(width 0.1)
				(type default)
			)
			(layer "F.Fab")
		)
		(pad "1" smd circle
			(at -0.40005 0 90)
			(size 0 0)
			(layers "F.Cu" "F.Mask" "F.Paste")
			(net "CLR_CMOS_N")
		)
		(pad "2" smd circle
			(at 0.40005 0 90)
			(size 0 0)
			(layers "F.Cu" "F.Mask" "F.Paste")
			(net "P1V5_BAT")
		)
	)
	(footprint ""
		(layer "F.Cu")
		(at 384.755136 -184.478168 -90)
		(property "Reference" "PR498"
			(at 0 0 270)
			(layer "F.SilkS")
			(hide yes)
			(effects
				(font
					(size 1.27 1.27)
				)
			)
		)
		(property "Value" ""
			(at 0 0 270)
			(layer "F.Fab")
			(effects
				(font
					(size 1.27 1.27)
				)
			)
		)
		(duplicate_pad_numbers_are_jumpers no)
		(fp_line
			(start -0.7874 0.4064)
			(end -0.7874 -0.4064)
			(stroke
				(width 0.1524)
				(type default)
			)
			(layer "F.SilkS")
		)
		(fp_line
			(start 0.7874 0.4064)
			(end -0.7874 0.4064)
			(stroke
				(width 0.1524)
				(type default)
			)
			(layer "F.SilkS")
		)
		(fp_line
			(start -0.7874 -0.4064)
			(end 0.7874 -0.4064)
			(stroke
				(width 0.1524)
				(type default)
			)
			(layer "F.SilkS")
		)
		(fp_line
			(start 0.7874 -0.4064)
			(end 0.7874 0.4064)
			(stroke
				(width 0.1524)
				(type default)
			)
			(layer "F.SilkS")
		)
		(fp_line
			(start -0.67945 0.3048)
			(end -0.67945 -0.305054)
			(stroke
				(width 0.1)
				(type default)
			)
			(layer "F.Fab")
		)
		(fp_line
			(start -0.12065 0.3048)
			(end -0.67945 0.3048)
			(stroke
				(width 0.1)
				(type default)
			)
			(layer "F.Fab")
		)
		(fp_line
			(start 0.120396 0.3048)
			(end 0.120396 0.2794)
			(stroke
				(width 0.1)
				(type default)
			)
			(layer "F.Fab")
		)
		(fp_line
			(start 0.67945 0.3048)
			(end 0.120396 0.3048)
			(stroke
				(width 0.1)
				(type default)
			)
			(layer "F.Fab")
		)
		(fp_line
			(start -0.12065 0.2794)
			(end -0.12065 0.3048)
			(stroke
				(width 0.1)
				(type default)
			)
			(layer "F.Fab")
		)
		(fp_line
			(start 0.120396 0.2794)
			(end -0.12065 0.2794)
			(stroke
				(width 0.1)
				(type default)
			)
			(layer "F.Fab")
		)
		(fp_line
			(start -0.12065 -0.2794)
			(end 0.12065 -0.2794)
			(stroke
				(width 0.1)
				(type default)
			)
			(layer "F.Fab")
		)
		(fp_line
			(start 0.12065 -0.2794)
			(end 0.12065 -0.3048)
			(stroke
				(width 0.1)
				(type default)
			)
			(layer "F.Fab")
		)
		(fp_line
			(start 0.12065 -0.3048)
			(end 0.67945 -0.3048)
			(stroke
				(width 0.1)
				(type default)
			)
			(layer "F.Fab")
		)
		(fp_line
			(start 0.67945 -0.3048)
			(end 0.67945 0.3048)
			(stroke
				(width 0.1)
				(type default)
			)
			(layer "F.Fab")
		)
		(fp_line
			(start -0.67945 -0.305054)
			(end -0.12065 -0.305054)
			(stroke
				(width 0.1)
				(type default)
			)
			(layer "F.Fab")
		)
		(fp_line
			(start -0.12065 -0.305054)
			(end -0.12065 -0.2794)
			(stroke
				(width 0.1)
				(type default)
			)
			(layer "F.Fab")
		)
		(pad "1" smd circle
			(at -0.40005 0 270)
			(size 0 0)
			(layers "F.Cu" "F.Mask" "F.Paste")
			(net "SW_PVDDCR_CPU0_P0_SW3_RC")
		)
		(pad "2" smd circle
			(at 0.40005 0 270)
			(size 0 0)
			(layers "F.Cu" "F.Mask" "F.Paste")
			(net "GND")
		)
	)
	(footprint ""
		(layer "F.Cu")
		(at 191.806322 -20.126452 180)
		(property "Reference" "PD116"
			(at -2.53746 2.96545 0)
			(unlocked yes)
			(layer "F.SilkS")
			(effects
				(font
					(size 0.7874 0.5842)
					(thickness 0.1524)
				)
				(justify left)
			)
		)
		(property "Value" ""
			(at 0 0 180)
			(layer "F.Fab")
			(effects
				(font
					(size 1.27 1.27)
				)
			)
		)
		(duplicate_pad_numbers_are_jumpers no)
		(fp_line
			(start 4.107942 1.459992)
			(end -3.400044 1.459992)
			(stroke
				(width 0.1524)
				(type default)
			)
			(layer "F.SilkS")
		)
		(fp_line
			(start 4.107942 -1.459992)
			(end 4.107942 1.459992)
			(stroke
				(width 0.1524)
				(type default)
			)
			(layer "F.SilkS")
		)
		(fp_line
			(start -3.400044 1.459992)
			(end -3.400044 -1.459992)
			(stroke
				(width 0.1524)
				(type default)
			)
			(layer "F.SilkS")
		)
		(fp_line
			(start -3.400044 -1.459992)
			(end 4.107942 -1.459992)
			(stroke
				(width 0.1524)
				(type default)
			)
			(layer "F.SilkS")
		)
		(fp_rect
			(start 4.107942 -1.459992)
			(end 3.308096 1.459992)
			(stroke
				(width 0)
				(type default)
			)
			(fill yes)
			(layer "F.SilkS")
		)
		(fp_line
			(start 2.29997 1.459992)
			(end -2.29997 1.459992)
			(stroke
				(width 0.1)
				(type default)
			)
			(layer "F.Fab")
		)
		(fp_line
			(start 2.29997 -1.459992)
			(end 2.29997 1.459992)
			(stroke
				(width 0.1)
				(type default)
			)
			(layer "F.Fab")
		)
		(fp_line
			(start -2.29997 1.459992)
			(end -2.29997 -1.459992)
			(stroke
				(width 0.1)
				(type default)
			)
			(layer "F.Fab")
		)
		(fp_line
			(start -2.29997 -1.459992)
			(end 2.29997 -1.459992)
			(stroke
				(width 0.1)
				(type default)
			)
			(layer "F.Fab")
		)
		(fp_text user "-"
			(at 5.50418 1.00203 0)
			(unlocked yes)
			(layer "F.SilkS")
			(effects
				(font
					(size 1.905 1.4224)
					(thickness 0.1524)
				)
				(justify left)
			)
		)
		(fp_text user "+"
			(at -5.283962 -0.182118 180)
			(unlocked yes)
			(layer "F.SilkS")
			(effects
				(font
					(size 1.905 1.4224)
					(thickness 0.1524)
				)
				(justify left)
			)
		)
		(fp_text user "-"
			(at 5.4102 0.29845 0)
			(unlocked yes)
			(layer "F.Fab")
			(effects
				(font
					(size 1.905 1.4224)
					(thickness 0.1524)
				)
				(justify left)
			)
		)
		(fp_text user "+"
			(at -4.7752 -0.12065 180)
			(unlocked yes)
			(layer "F.Fab")
			(effects
				(font
					(size 1.905 1.4224)
					(thickness 0.1524)
				)
				(justify left)
			)
		)
		(pad "A" smd rect
			(at -1.999996 0 270)
			(size 1.7018 2.5146)
			(layers "F.Cu" "F.Mask" "F.Paste")
			(net "GND")
		)
		(pad "C" smd rect
			(at 1.999996 0 270)
			(size 1.7018 2.5146)
			(layers "F.Cu" "F.Mask" "F.Paste")
			(net "P12V_SCM_R")
		)
	)
)
